# BASEBOARD_FAB2 (Tioga Pass) — schematic parts with pin connectivity, parts 2515–2672 of 4751; source: Cadence DE-HDL packaged netlist (pstxprt.dat, pstxnet.dat, pstchip.dat)

Q12W4  BSL308C-H6327-GP  pkg DISCRET-GB1  page 197
  1  \gate#1\  UNSPEC  = PWRGD_PVDDQ_KLM
  2  \source#2\  UNSPEC  = P12V_NVDIMM_KLM
  3  \gate#3\  UNSPEC  = PWRGD_PVDDQ_KLM_N
  4  \drain#4\  UNSPEC  = P12V_NVDIMM_KLM_D
  5  \source#5\  UNSPEC  = GND
  6  \drain#6\  UNSPEC  = PWRGD_PVDDQ_KLM_N

Q25W4  FET_N_DUAL  2N7002DW FET  pkg SMLF  page 252
  1  SOURCE(0)  UNSPEC  = I2C_BMC_VGA_DDC_SCL
  2  GATE(0)  UNSPEC  = Q25W1_GATE
  3  DRAIN(0)  UNSPEC  = I2C_BMC_VGA_DDC_SDA_G
  4  SOURCE(0)  UNSPEC  = I2C_BMC_VGA_DDC_SDA
  5  GATE(0)  UNSPEC  = Q25W2_GATE
  6  DRAIN(0)  UNSPEC  = I2C_BMC_VGA_DDC_SCL_G

Q25W5  FET_N  2N7002 FET  pkg SOT23LF  page 255
  1  GATE  UNSPEC  = BMC_JTAG_SEL_N
  2  SRC  UNSPEC  = GND
  3  DRN  UNSPEC  = BMC_JTAG_SEL

R1A1  RES  120.0 1% CHIP  pkg 0603  page 228 : 1 = PVDDQ_KLM ; 2 = GND
R1A2  RES  68.1K 1% EMPTY  pkg 0402  page 227 : 1 = VR_PVDDQ_KLM_PH2_OCSET ; 2 = GND
R1A3  RES  68.1K 1% EMPTY  pkg 0402  page 227 : 1 = VR_PVDDQ_KLM_PH1_OCSET ; 2 = GND
R1B1  RES  1.00K 1% CHIP  pkg 0402  page 226 : 1 = P3V3_STBY ; 2 = IRQ_PVDDQ_KLM_VRHOT_LVT3_R_N
R1B2  RES  1.00K 1% CHIP  pkg 0402  page 226 : 1 = P3V3_STBY ; 2 = PWRGD_PVDDQ_KLM_R
R1B4  RES  33.2 1% CHIP  pkg 0402  page 226 : 1 = IRQ_PVDDQ_KLM_VRHOT_LVT3_R_N ; 2 = IRQ_PVDDQ_KLM_VRHOT_LVT3_N
R1B5  RES  22.1 1.0% CHIP  pkg 0402  page 226 : 1 = PWRGD_PVDDQ_KLM_R ; 2 = PWRGD_PVDDQ_KLM
R1B8  RES  150.0 1% CHIP  pkg 0402  page 226 : 1 = SVID_CLK1_CPU1_R ; 2 = SVID_CLK_PVDDQ_KLM
R1B10  RES  0.0 5% CHIP  pkg 0402  page 226 : 1 = SVID_VDIO_PVDDQ_KLM ; 2 = SVID_DIO1_CPU1_R
R1B11  RES  0.0 5% CHIP  pkg 0402  page 226 : 1 = SVID_ALERT_PVDDQ_KLM ; 2 = SVID_ALERT1_CPU1_R_N
R1B12  RES  16K 1.0% CHIP  pkg 0402  page 226 : 1 = VR_PVDDQ_KLM_XADDR1 ; 2 = GND
R1B13  RES  2.26K 1.0% CHIP  pkg 0402  page 226 : 1 = P3V3_STBY ; 2 = PWRGD_PVDDQ_KLM
R1B15  RES  3.16K 1% CHIP  pkg 0402  page 226 : 1 = VR_PVDDQ_KLM_XADDR2 ; 2 = GND
R1B16  RES  10.0 1% CHIP  pkg 0402  page 226 : 1 = VSENSE_PVDDQ_KLM_P ; 2 = VR_PVDDQ_KLM_AVSP
R1B21  RES  4.75K 1% CHIP  pkg 0402  page 161 : 1 = P3V3_STBY ; 2 = FAN_TACH2
R1B22  RES  100.0 1% CHIP  pkg 0402  page 161 : 1 = FAN_TACH2 ; 2 = FAN_TACH2_CPU1_D2
R1C1  RES  221 1.0% CHIP  pkg 0402  page 55 : 1 = SVID_ALERT1_CPU1_N ; 2 = SVID_ALERT1_CPU1_R_N
R1C2  RES  0.0 5% CHIP  pkg 0402  page 55 : 1 = SVID_DIO1_CPU1 ; 2 = SVID_DIO1_CPU1_R
R1C3  RES  0.0 5% CHIP  pkg 0402  page 55 : 1 = SVID_CLK1_CPU1 ; 2 = SVID_CLK1_CPU1_R
R1C4  RES  100.0 1% CHIP  pkg 0402  page 210 : 1 = VSENSE_PVSA_CPU1_N ; 2 = GND
R1C5  RES  0.0 5% CHIP  pkg 0402  page 210 : 1 = VSENSE_PVSA_CPU1_N ; 2 = VSENSE_PVSA_CPU1_SKT_VRTN
R1C6  RES  1.00K 1% EMPTY  pkg 0402  page 210 : 1 = VSENSE_PVSA_CPU1_P ; 2 = VSENSE_PVSA_CPU1_N
R1C7  RES  0.0 5% CHIP  pkg 0402  page 210 : 1 = VSENSE_PVSA_CPU1_P ; 2 = VSENSE_PVSA_CPU1_SKT_VSEN
R1C9  RES  0.0 5% EMPTY  pkg 0402  page 182 : 1 = IRQ_BOARD_BMC_ALERT_N ; 2 = FAN_TACH2_R
R1C10  RES  0.0 5% EMPTY  pkg 0402  page 182 : 1 = SMB_LAN_STBY_LVC3_SDA ; 2 = FAN_TACH3_R
R1C11  RES  0.0 5% EMPTY  pkg 0402  page 182 : 1 = SMB_LAN_STBY_LVC3_SCL ; 2 = FAN_TACH1_R
R1C12  RES  100.0 1% CHIP  pkg 0402  page 210 : 1 = VSENSE_PVSA_CPU1_P ; 2 = PVSA_CPU1
R1C13  RES  100.0K 1% CHIP  pkg 0402  page 206 : 1 = VR_FET_SW_P12V_STBY_PVCCIN_CPU1 ; 2 = VR_PVCCIN_CPU1_AVINSEN
R1C14  RES  0.0 5% CHIP  pkg 0402  page 206 : 1 = P3V3_STBY ; 2 = VR_PVCCIN_CPU1_VDD
R1C16  RES  1.5K 1% CHIP  pkg 0402  page 206 : 1 = VR_PVCCIN_CPU1_AVINSEN ; 2 = GND
R1C18  RES  2.26K 1.0% EMPTY  pkg 0402  page 206 : 1 = P3V3_STBY ; 2 = PU_VR_PVCCIN_CPU1_IMON
R1C21  RES  10.0 1% CHIP  pkg 0402  page 206 : 1 = VSENSE_PVSA_CPU1_P ; 2 = VSENSE_PVSA_CPU1_BVSP
R1C28  RES  1.00K 1% CHIP  pkg 0402  page 206 : 1 = P3V3_STBY ; 2 = VR_VRRDY_PVCCIN_CPU1
R1C30  RES  22.1 1.0% CHIP  pkg 0402  page 206 : 1 = VR_VRRDY_PVCCIN_CPU1 ; 2 = PWRGD_PVCCIN_CPU1
R1C31  RES  0.0 5% EMPTY  pkg 0402  page 182 : 1 = FM_XRC_READY_N ; 2 = FAN_TACH0_R
R1C32  RES  1.00K 1% CHIP  pkg 0402  page 156 : 1 = GND ; 2 = PD_PIROM_CPU1_ADDR2
R1C33  RES  1.00K 1% CHIP  pkg 0402  page 156 : 1 = GND ; 2 = PD_PIROM_CPU1_ADDR1
R1C34  RES  10.0K 1% CHIP  pkg 0402  page 156 : 1 = P3V3_STBY ; 2 = PU_PIROM_CPU1_ADDR0
R1C35  RES  3.32K 1% EMPTY  pkg 0402  page 156 : 1 = P3V3_STBY ; 2 = FM_CPU1_SM_WP
R1C36  RES  1.00K 1% CHIP  pkg 0402  page 156 : 1 = FM_CPU1_SM_WP ; 2 = GND
R1C37  RES  68.1K 1% EMPTY  pkg 0402  page 210 : 1 = VR_PVSA_CPU1_OCSET ; 2 = GND
R1D1  RES  33.2 1% CHIP  pkg 0402  page 206 : 1 = PWRGD_PVSA_CPU1_R ; 2 = PWRGD_PVSA_CPU1
R1D2  RES  0.0 5% CHIP  pkg 0402  page 206 : 1 = SVID_VDIO_PVCCIN_CPU1 ; 2 = SVID_DIO0_CPU1_R
R1D3  RES  0.0 5% CHIP  pkg 0402  page 206 : 1 = SVID_VALERT_VCCIN_CPU1 ; 2 = SVID_ALERT0_CPU1_R_N
R1D4  RES  10.0 1% CHIP  pkg 0402  page 206 : 1 = VSENSE_PVCCIN_CPU1_P ; 2 = VSENSE_PVCCIN_CPU1_AVSP
R1D6  RES  1.00K 1% CHIP  pkg 0402  page 206 : 1 = P3V3_STBY ; 2 = IRQ_PVCCIN_CPU1_VRHOT_LVC3_R_N
R1D7  RES  1.00K 1% CHIP  pkg 0402  page 206 : 1 = P3V3_STBY ; 2 = FM_PVCCIN_CPU1_PWR_IN_ALERT_N
R1D8  RES  1.00K 1% CHIP  pkg 0402  page 206 : 1 = P3V3_STBY ; 2 = PWRGD_PVSA_CPU1_R
R1D9  RES  150.0 1% CHIP  pkg 0402  page 206 : 1 = SVID_CLK0_CPU1_R ; 2 = SVID_VCLK_PVCCIN_CPU1
R1D10  RES  10.0K 1% CHIP  pkg 0402  page 200 : 1 = P3V3_STBY ; 2 = A_HSC_LOW_GATE
R1D11  RES  100.0K 1% CHIP  pkg 0402  page 199 : 1 = A_HSC_LOW_EN ; 2 = AGND_HSC
R1D12  RES  10.0K 1% CHIP  pkg 0402  page 200 : 1 = A_HSC_LOW ; 2 = AGND_HSC
R1D13  RES  90.9K 1% CHIP  pkg 0402  page 199 : 1 = A_HSC_ISET_S ; 2 = A_HSC_ISET
R1D14  RES  105.0K 1% CHIP  pkg 0402  page 200 : 1 = A_HSC_CSOUT ; 2 = A_HSC_LOW
R1D15  RES  100.0K 1% CHIP  pkg 0402  page 199 : 1 = P12V_PSU ; 2 = A_HSC_OCP_SEL
R1D16  RES  69.8K 1% CHIP  pkg 0402  page 199 : 1 = A_HSC_ISET ; 2 = A_HSC_ISET_S2
R1D18  RES  100.0K 1% CHIP  pkg 0402  page 199 : 1 = A_HSC_HIGH_EN ; 2 = AGND_HSC
R1D19  RES  10.0K 1% CHIP  pkg 0402  page 200 : 1 = A_HSC_HIGH ; 2 = AGND_HSC
R1D20  RES  200.0K 1% CHIP  pkg 0402  page 200 : 1 = A_HSC_CSOUT ; 2 = A_HSC_HIGH
R1D21  RES  4.75K 1% CHIP  pkg 0402  page 200 : 1 = P3V3_STBY ; 2 = FM_OC_DETECT_EN
R1D22  RES  10.0K 1% CHIP  pkg 0402  page 200 : 1 = P3V3_STBY ; 2 = FM_OC_DETECT_N
R1D23  RES  10.0K 1% CHIP  pkg 0402  page 200 : 1 = P3V3_STBY ; 2 = IRQ_OC_DETECT_N
R1D24  RES  0.0 5% CHIP  pkg 0402  page 199 : 1 = SMB_BMC_PMBUS_STBY_LVC3_SCL ; 2 = SMB_3V3SB_HSC_SCL_R
R1D25  RES  0.0 5% CHIP  pkg 0402  page 199 : 1 = SMB_BMC_PMBUS_STBY_LVC3_SDA ; 2 = SMB_3V3SB_HSC_SDA_R
R1D26  RES  33.2 1% CHIP  pkg 0402  page 199 : 1 = IRQ_SML1_PMBUS_ALERT_R_N ; 2 = IRQ_SML1_PMBUS_ALERT_N
R1D27  RES  4.75K 1% EMPTY  pkg 0402  page 199 : 1 = A_HSC_VCAP ; 2 = FM_P12V_HSC_ADR2
R1D28  RES  100.0 1% EMPTY  pkg 0402  page 199 : 1 = PD_HSC_RETRY_N ; 2 = AGND_HSC
R1D29  RES  4.75K 1% CHIP  pkg 0402  page 199 : 1 = A_HSC_VCAP ; 2 = FM_P12V_HSC_ADR1
R1D30  RES  33.2 1% CHIP  pkg 0402  page 199 : 1 = IRQ_HSC_FAULT_R_N ; 2 = IRQ_HSC_FAULT_N
R1D31  RES  6.19K 1% CHIP  pkg 0402  page 199 : 1 = PWRGD_P12V_R ; 2 = GND
R1D32  RES  100.0K 1% CHIP  pkg 0402  page 199 : 1 = A_HSC_VCAP ; 2 = A_HSC_ISTART
R1D33  RES  33.2 1% CHIP  pkg 0402  page 199 : 1 = PWRGD_P12V_R ; 2 = PWRGD_P12V_HSC
R1D34  RES  16K 1.0% CHIP  pkg 0402  page 199 : 1 = A_HSC_ISTART ; 2 = AGND_HSC
R1D35  RES  4.75K 1% CHIP  pkg 0402  page 126 : 1 = P3V3_STBY ; 2 = FM_OC_DETECT_EN_N
R1D36  RES  1.00K 1% CHIP  pkg 0402  page 199 : 1 = P12V_STBY ; 2 = A_HSC_VOUT
R1D37  RES  100.0K 1% CHIP  pkg 0402  page 199 : 1 = A_HSC_VCAP ; 2 = A_HSC_ISET
R1D39  RES  100.0K 1% CHIP  pkg 0402  page 199 : 1 = A_HSC_VCAP ; 2 = A_HSC_PSET
R1D40  RES  40.2K 1% CHIP  pkg 0402  page 199 : 1 = A_HSC_PSET ; 2 = AGND_HSC
R1D41  RES  0.0 5% CHIP  pkg 0805  page 199 : 1 = GND ; 2 = AGND_HSC
R1D42  RES  11K 1% CHIP  pkg 0402  page 199 : 1 = A_HSC_UV ; 2 = AGND_HSC
R1D43  RES  7.5K 1% CHIP  pkg 0402  page 199 : 1 = A_HSC_OV ; 2 = AGND_HSC
R1D44  RES  0.0 5% CHIP  pkg 0402  page 200 : 1 = A_HSC_MOP ; 2 = A_HSC_HSP
R1D45  RES  0.0 5% CHIP  pkg 0402  page 200 : 1 = A_HSC_MON ; 2 = A_HSC_HSN
R1D46  RES  10.0 1% CHIP  pkg 0402  page 200 : 1 = P12V_HSC_SENP0 ; 2 = A_HSC_HSP
R1D47  RES  10.0 1% CHIP  pkg 0402  page 200 : 1 = P12V_HSC_SENN0 ; 2 = A_HSC_HSN
R1D48  RES  10.0 1% CHIP  pkg 0402  page 200 : 1 = A_HSC_GATE ; 2 = A_HSC_GATE3_R

R1D49  RES_PWR  0.001 1% CHIP  pkg 6PAD  page 200
  1  \1\  UNSPEC  = P12V_PSU
  2  \2\  UNSPEC  = P12V_MB0_SW
  3  \3\  UNSPEC  = P12V_HSC_SENP0
  4  \4\  UNSPEC  = P12V_HSC_SENN0
  5  \5\  UNSPEC  = P12V_PSU
  6  \6\  UNSPEC  = P12V_MB0_SW

R1D51  RES  10.0 1% CHIP  pkg 0402  page 200 : 1 = A_HSC_C ; 2 = A_HSC_GATE
R1D52  RES  68.1K 1% EMPTY  pkg 0402  page 209 : 1 = VR_PVCCIN_CPU1_PH5_OCSET ; 2 = GND
R1D53  RES  2.26K 1.0% EMPTY  pkg 0402  page 206 : 1 = P3V3_STBY ; 2 = PU_VR_PVCCIN_CPU1_FLT1_SMBALT_N
R1D54  RES  68.1K 1% EMPTY  pkg 0402  page 208 : 1 = VR_PVCCIN_CPU1_PH4_OCSET ; 2 = GND
R1D55  RES  68.1K 1% EMPTY  pkg 0402  page 208 : 1 = VR_PVCCIN_CPU1_PH3_OCSET ; 2 = GND
R1E1  RES  10.0 1% CHIP  pkg 0402  page 200 : 1 = A_HSC_GATE ; 2 = A_HSC_GATE1_R
R1E3  RES  100.0 1% CHIP  pkg 0603  page 208 : 1 = PVCCIN_CPU1 ; 2 = GND
R1E4  RES  100.0 1% CHIP  pkg 0402  page 209 : 1 = VSENSE_PVCCIN_CPU1_P ; 2 = PVCCIN_CPU1
R1E5  RES  1.00K 1% EMPTY  pkg 0402  page 209 : 1 = VSENSE_PVCCIN_CPU1_P ; 2 = VSENSE_PVCCIN_CPU1_N
R1E6  RES  0.0 5% CHIP  pkg 0402  page 209 : 1 = VSENSE_PVCCIN_CPU1_P ; 2 = VSENSE_PVCCIN_CPU1_SKT_VSEN
R1E7  RES  0.0 5% CHIP  pkg 0402  page 209 : 1 = VSENSE_PVCCIN_CPU1_N ; 2 = VSENSE_PVCCIN_CPU1_SKT_VRTN
R1E8  RES  100.0 1% CHIP  pkg 0402  page 209 : 1 = VSENSE_PVCCIN_CPU1_N ; 2 = GND
R1E9  RES  1.00K 1% CHIP  pkg 0402  page 167 : 1 = P3V3_STBY ; 2 = PU_TMP421_2_A0
R1E10  RES  1.00K 1% CHIP  pkg 0402  page 167 : 1 = P3V3_STBY ; 2 = PD_TMP421_2_A1
R1E11  RES  10.0K 1% EMPTY  pkg 0402  page 161 : 1 = P3V3_STBY ; 2 = FM_ENABLE_FAN_POWER
R1E12  RES  4.75K 1% CHIP  pkg 0402  page 161 : 1 = P5V_STBY ; 2 = FAN_PWM_OUT_SYS0_R
R1E13  RES  68.1K 1% EMPTY  pkg 0402  page 207 : 1 = VR_PVCCIN_CPU1_PH2_OCSET ; 2 = GND
R1E14  RES  68.1K 1% EMPTY  pkg 0402  page 207 : 1 = VR_PVCCIN_CPU1_PH1_OCSET ; 2 = GND
R1F1  RES  4.75K 1% CHIP  pkg 0402  page 161 : 1 = P3V3_STBY ; 2 = FAN_TACH0
R1F2  RES  100.0 1% CHIP  pkg 0402  page 161 : 1 = FAN_TACH0 ; 2 = FAN_TACH0_CPU0_D2
R1F3  RES  0.002 1% CHIP  pkg 1206  page 197 : 1 = P12V_STBY ; 2 = P12V_NVDIMM_GHJ
R1F4  RES  2 1.0% CHIP  pkg 0402  page 100 : 1 = M_G_CPU_VREF ; 2 = M_G_VREF
R1F5  RES  1.00K 1% CHIP  pkg 0402  page 100 : 1 = PVDDQ_GHJ ; 2 = M_G_VREF
R1F6  RES  1.00K 1% CHIP  pkg 0402  page 100 : 1 = M_G_VREF ; 2 = GND
R1F8  RES  0.0 5% CHIP  pkg 0402  page 181 : 1 = FAN_TACH0 ; 2 = FAN_TACH0_R
R1F9  RES  0.0 5% EMPTY  pkg 0402  page 182 : 1 = FM_BMC_READY_N ; 2 = FAN_PWM_OUT_SYS0_R1
R1G1  RES  2 1.0% CHIP  pkg 0402  page 100 : 1 = M_H_CPU_VREF ; 2 = M_H_VREF
R1G2  RES  1.00K 1% CHIP  pkg 0402  page 100 : 1 = PVDDQ_GHJ ; 2 = M_H_VREF
R1G3  RES  1.00K 1% CHIP  pkg 0402  page 100 : 1 = M_H_VREF ; 2 = GND
R1G5  RES  10.0 1% CHIP  pkg 0402  page 223 : 1 = VSENSE_PVDDQ_GHJ_P ; 2 = VR_PVDDQ_GHJ_AVSP
R1G6  RES  2.26K 1.0% CHIP  pkg 0402  page 223 : 1 = P3V3_STBY ; 2 = PWRGD_PVDDQ_GHJ
R1G7  RES  150.0 1% CHIP  pkg 0402  page 223 : 1 = SVID_CLK1_CPU1_R ; 2 = SVID_CLK_PVDDQ_GHJ
R1G8  RES  33.2 1% CHIP  pkg 0402  page 223 : 1 = IRQ_PVDDQ_GHJ_VRHOT_LVT3_R_N ; 2 = IRQ_PVDDQ_GHJ_VRHOT_LVT3_N
R1G9  RES  0.0 5% CHIP  pkg 0402  page 223 : 1 = SVID_ALERT_PVDDQ_GHJ ; 2 = SVID_ALERT1_CPU1_R_N
R1G10  RES  0.0 5% CHIP  pkg 0402  page 223 : 1 = SVID_VDIO_PVDDQ_GHJ ; 2 = SVID_DIO1_CPU1_R
R1G11  RES  1.00K 1% CHIP  pkg 0402  page 223 : 1 = P3V3_STBY ; 2 = IRQ_PVDDQ_GHJ_VRHOT_LVT3_R_N
R1G12  RES  22.1 1.0% CHIP  pkg 0402  page 223 : 1 = PWRGD_PVDDQ_GHJ_R ; 2 = PWRGD_PVDDQ_GHJ
R1G14  RES  2 1.0% CHIP  pkg 0402  page 100 : 1 = M_J_CPU_VREF ; 2 = M_J_VREF
R1G15  RES  1.00K 1% CHIP  pkg 0402  page 100 : 1 = PVDDQ_GHJ ; 2 = M_J_VREF
R1G16  RES  1.00K 1% CHIP  pkg 0402  page 223 : 1 = P3V3_STBY ; 2 = PWRGD_PVDDQ_GHJ_R
R1G17  RES  1.00K 1% CHIP  pkg 0402  page 100 : 1 = M_J_VREF ; 2 = GND
R1G20  RES  120.0 1% CHIP  pkg 0603  page 225 : 1 = PVDDQ_GHJ ; 2 = GND
R1G22  RES  3.16K 1% CHIP  pkg 0402  page 223 : 1 = VR_PVDDQ_GHJ_XADDR2 ; 2 = GND
R1G23  RES  5.36K 1.0% CHIP  pkg 0402  page 223 : 1 = VR_PVDDQ_GHJ_XADDR1 ; 2 = GND
R1G25  RES  68.1K 1% EMPTY  pkg 0402  page 224 : 1 = VR_PVDDQ_GHJ_PH2_OCSET ; 2 = GND
R1G26  RES  68.1K 1% EMPTY  pkg 0402  page 224 : 1 = VR_PVDDQ_GHJ_PH1_OCSET ; 2 = GND
R1L2  RES  10.0 1% CHIP  pkg 0402  page 155 : 1 = FM_CPLD_DBG_PWR_EN_N ; 2 = FM_CPLD_DBG_PWR_EN_R_N
R1L6  RES  0.0 5% CHIP  pkg 0402  page 168 : 1 = FM_UART_SWITCH_N ; 2 = FM_DB_UART_SEL0_N
R1L7  RES  4.75K 1% CHIP  pkg 0402  page 157 : 1 = P3V3_STBY ; 2 = FM_BMC_CPLD_MP_RST_N
R1L8  RES  470.0 5% CHIP  pkg 0402  page 175 : 1 = P5V_STBY ; 2 = FP_ID_LED_XOR_R
R1L9  RES  100.0K 1% CHIP  pkg 0402  page 155 : 1 = P12V_STBY ; 2 = FM_CPLD_DBG_PWR_EN
R1L11  RES  10.0 1% CHIP  pkg 0402  page 155 : 1 = LED_POSTCODE_7 ; 2 = LED_POSTCODE_7_R
R1L12  RES  0.0 5% CHIP  pkg 0402  page 175 : 1 = PWRGD_P3V3 ; 2 = PWRGD_P3V3_R
R1L13  RES  1.00K 1% CHIP  pkg 0402  page 111 : 1 = XDP_SYSPWROK ; 2 = P3V3_STBY
R1L14  RES  10.0 1% CHIP  pkg 0402  page 155 : 1 = LED_POSTCODE_6 ; 2 = LED_POSTCODE_6_R
R1L15  RES  150.0 1% CHIP  pkg 0402  page 112 : 1 = PVCCIO_CPU0 ; 2 = XDP_CPU_TMS
R1L16  RES  49.9 1% CHIP  pkg 0402  page 196 : 1 = PWRGD_P3V3_R1 ; 2 = PWRGD_P3V3
R1L17  RES  150.0 1% CHIP  pkg 0402  page 111 : 1 = XDP_CPU_PWR_DEBUG_N ; 2 = PVCCIO_CPU0
R1L18  RES  10.0 1% CHIP  pkg 0402  page 155 : 1 = LED_POSTCODE_5 ; 2 = LED_POSTCODE_5_R
R1L19  RES  4.75K 1% CHIP  pkg 0402  page 175 : 1 = P3V3_STBY ; 2 = FM_DEBUG_RST_BTN_N
R1L20  RES  10.0 1% CHIP  pkg 0402  page 155 : 1 = LED_POSTCODE_4 ; 2 = LED_POSTCODE_4_R
R1L21  RES  64.9 1.0% CHIP  pkg 0402  page 177 : 1 = P3V3 ; 2 = FP_LED_HDD_ACTIVITY_AND_R_N
R1L22  RES  200.0 1% CHIP  pkg 0402  page 175 : 1 = FM_DEBUG_RST_BTN_N ; 2 = FP_RST_BTN_R_N
R1L23  RES  1.00K 1% CHIP  pkg 0402  page 111 : 1 = XDP_PWRGD_RST_N ; 2 = P3V3_STBY
R1L24  RES  10.0 1% CHIP  pkg 0402  page 155 : 1 = LED_POSTCODE_3 ; 2 = LED_POSTCODE_3_R
R1L25  RES  10.0 1% CHIP  pkg 0402  page 155 : 1 = LED_POSTCODE_2 ; 2 = LED_POSTCODE_2_R
R1L26  RES  33.2 1% CHIP  pkg 0402  page 175 : 1 = FM_PWR_BTN_R_N ; 2 = FM_PWR_BTN_N
R1L27  RES  4.75K 1% CHIP  pkg 0402  page 175 : 1 = P3V3_STBY ; 2 = FP_PWR_BTN_R_N
